# T6G (Grand Teton) — schematic netlist excerpt (pin names and nets, part order shuffled) for the footprints in the layout excerpt that follows; sources: Cadence DE-HDL packaged netlist, KiCad conversion of 04192023_DAF0TMB3IC0_F0TG_MB_C_brd_V02_OCP.brd

R6074  Q_RES  0 5% CHIP  pkg 0402LF  page 85 : A = FM_THERMAL_ALERT_N ; B = FM_THERMAL_ALERT_R_N
C57  Q_CAP  10UF 16V 10% EMPTY  pkg C0805  page 188 : A = P5V_AUX ; B = GND

(kicad_pcb
	(version 20260206)
	(generator "pcbnew")
	(generator_version "10.0")
	(general
		(thickness 1.6)
		(legacy_teardrops no)
	)
	(paper "A4")
	(title_block
		(title "04192023_DAF0TMB3IC0_F0TG_MB_C_brd_V02_OCP.brd")
		(comment 1 "Grand Teton / footprints 3014-3015 of 8354")
	)
	(layers
		(0 "F.Cu" signal "TOP")
		(4 "In1.Cu" signal "GND")
		(6 "In2.Cu" signal "IN1")
		(8 "In3.Cu" signal "GND1")
		(10 "In4.Cu" signal "IN2")
		(12 "In5.Cu" signal "GND2")
		(14 "In6.Cu" signal "IN3")
		(16 "In7.Cu" signal "GND3")
		(18 "In8.Cu" signal "VCC")
		(20 "In9.Cu" signal "VCC1")
		(22 "In10.Cu" signal "GND4")
		(24 "In11.Cu" signal "IN4")
		(26 "In12.Cu" signal "GND5")
		(28 "In13.Cu" signal "IN5")
		(30 "In14.Cu" signal "GND6")
		(32 "In15.Cu" signal "IN6")
		(34 "In16.Cu" signal "GND7")
		(2 "B.Cu" signal "BOTTOM")
		(9 "F.Adhes" user "F.Adhesive")
		(11 "B.Adhes" user "B.Adhesive")
		(13 "F.Paste" user "Package Geometry/Pastemask Top")
		(15 "B.Paste" user "Package Geometry/Pastemask Bottom")
		(5 "F.SilkS" user "Ref Des/Silkscreen Top")
		(7 "B.SilkS" user "Ref Des/Silkscreen Bottom")
		(1 "F.Mask" user "Board Geometry/Soldermask Top")
		(3 "B.Mask" user "Board Geometry/Soldermask Bottom")
		(17 "Dwgs.User" user "User.Drawings")
		(19 "Cmts.User" user "User.Comments")
		(21 "Eco1.User" user "User.Eco1")
		(23 "Eco2.User" user "User.Eco2")
		(25 "Edge.Cuts" user "Board Geometry/Outline")
		(27 "Margin" user)
		(31 "F.CrtYd" user "Package Geometry/Place Bound Top")
		(29 "B.CrtYd" user "Package Geometry/Place Bound Bottom")
		(35 "F.Fab" user "Ref Des/Assembly Top")
		(33 "B.Fab" user "Ref Des/Assembly Bottom")
	)
	(footprint ""
		(layer "F.Cu")
		(at 183.769 -92.674948 90)
		(property "Reference" "R6074"
			(at 0 0 90)
			(layer "F.SilkS")
			(hide yes)
			(effects
				(font
					(size 1.27 1.27)
				)
			)
		)
		(property "Value" ""
			(at 0 0 90)
			(layer "F.Fab")
			(effects
				(font
					(size 1.27 1.27)
				)
			)
		)
		(duplicate_pad_numbers_are_jumpers no)
		(fp_line
			(start 0.7874 -0.4064)
			(end 0.7874 0.4064)
			(stroke
				(width 0.1524)
				(type default)
			)
			(layer "F.SilkS")
		)
		(fp_line
			(start -0.7874 -0.4064)
			(end 0.7874 -0.4064)
			(stroke
				(width 0.1524)
				(type default)
			)
			(layer "F.SilkS")
		)
		(fp_line
			(start 0.7874 0.4064)
			(end -0.7874 0.4064)
			(stroke
				(width 0.1524)
				(type default)
			)
			(layer "F.SilkS")
		)
		(fp_line
			(start -0.7874 0.4064)
			(end -0.7874 -0.4064)
			(stroke
				(width 0.1524)
				(type default)
			)
			(layer "F.SilkS")
		)
		(fp_line
			(start -0.12065 -0.305054)
			(end -0.12065 -0.2794)
			(stroke
				(width 0.1)
				(type default)
			)
			(layer "F.Fab")
		)
		(fp_line
			(start -0.67945 -0.305054)
			(end -0.12065 -0.305054)
			(stroke
				(width 0.1)
				(type default)
			)
			(layer "F.Fab")
		)
		(fp_line
			(start 0.67945 -0.3048)
			(end 0.67945 0.3048)
			(stroke
				(width 0.1)
				(type default)
			)
			(layer "F.Fab")
		)
		(fp_line
			(start 0.12065 -0.3048)
			(end 0.67945 -0.3048)
			(stroke
				(width 0.1)
				(type default)
			)
			(layer "F.Fab")
		)
		(fp_line
			(start 0.12065 -0.2794)
			(end 0.12065 -0.3048)
			(stroke
				(width 0.1)
				(type default)
			)
			(layer "F.Fab")
		)
		(fp_line
			(start -0.12065 -0.2794)
			(end 0.12065 -0.2794)
			(stroke
				(width 0.1)
				(type default)
			)
			(layer "F.Fab")
		)
		(fp_line
			(start 0.120396 0.2794)
			(end -0.12065 0.2794)
			(stroke
				(width 0.1)
				(type default)
			)
			(layer "F.Fab")
		)
		(fp_line
			(start -0.12065 0.2794)
			(end -0.12065 0.3048)
			(stroke
				(width 0.1)
				(type default)
			)
			(layer "F.Fab")
		)
		(fp_line
			(start 0.67945 0.3048)
			(end 0.120396 0.3048)
			(stroke
				(width 0.1)
				(type default)
			)
			(layer "F.Fab")
		)
		(fp_line
			(start 0.120396 0.3048)
			(end 0.120396 0.2794)
			(stroke
				(width 0.1)
				(type default)
			)
			(layer "F.Fab")
		)
		(fp_line
			(start -0.12065 0.3048)
			(end -0.67945 0.3048)
			(stroke
				(width 0.1)
				(type default)
			)
			(layer "F.Fab")
		)
		(fp_line
			(start -0.67945 0.3048)
			(end -0.67945 -0.305054)
			(stroke
				(width 0.1)
				(type default)
			)
			(layer "F.Fab")
		)
		(pad "1" smd circle
			(at -0.40005 0 90)
			(size 0 0)
			(layers "F.Cu" "F.Mask" "F.Paste")
			(net "FM_THERMAL_ALERT_N")
		)
		(pad "2" smd circle
			(at 0.40005 0 90)
			(size 0 0)
			(layers "F.Cu" "F.Mask" "F.Paste")
			(net "FM_THERMAL_ALERT_R_N")
		)
	)
	(footprint ""
		(layer "F.Cu")
		(at 403.961346 -142.871952 -90)
		(property "Reference" "C57"
			(at 0 0 270)
			(layer "F.SilkS")
			(hide yes)
			(effects
				(font
					(size 1.27 1.27)
				)
			)
		)
		(property "Value" ""
			(at 0 0 270)
			(layer "F.Fab")
			(effects
				(font
					(size 1.27 1.27)
				)
			)
		)
		(duplicate_pad_numbers_are_jumpers no)
		(fp_line
			(start -1.524 0.762)
			(end -1.524 -0.762)
			(stroke
				(width 0.1524)
				(type default)
			)
			(layer "F.SilkS")
		)
		(fp_line
			(start 1.524 0.762)
			(end -1.524 0.762)
			(stroke
				(width 0.1524)
				(type default)
			)
			(layer "F.SilkS")
		)
		(fp_line
			(start -1.524 -0.762)
			(end 1.524 -0.762)
			(stroke
				(width 0.1524)
				(type default)
			)
			(layer "F.SilkS")
		)
		(fp_line
			(start 1.524 -0.762)
			(end 1.524 0.762)
			(stroke
				(width 0.1524)
				(type default)
			)
			(layer "F.SilkS")
		)
		(fp_line
			(start -1.1049 0.724916)
			(end 1.1049 0.724916)
			(stroke
				(width 0.1)
				(type default)
			)
			(layer "F.Fab")
		)
		(fp_line
			(start 1.1049 0.724916)
			(end 1.1049 -0.724916)
			(stroke
				(width 0.1)
				(type default)
			)
			(layer "F.Fab")
		)
		(fp_line
			(start -1.1049 -0.724916)
			(end -1.1049 0.724916)
			(stroke
				(width 0.1)
				(type default)
			)
			(layer "F.Fab")
		)
		(fp_line
			(start 1.1049 -0.724916)
			(end -1.1049 -0.724916)
			(stroke
				(width 0.1)
				(type default)
			)
			(layer "F.Fab")
		)
		(pad "1" smd rect
			(at -0.889 0 90)
			(size 1.016 1.27)
			(layers "F.Cu" "F.Mask" "F.Paste")
			(net "P5V_AUX")
		)
		(pad "2" smd rect
			(at 0.889 0 90)
			(size 1.016 1.27)
			(layers "F.Cu" "F.Mask" "F.Paste")
			(net "GND")
		)
	)
)
